G04 ================== begin FILE IDENTIFICATION RECORD ==================*
G04 Layout Name:  13919-sa.brd*
G04 Film Name:    TSMD*
G04 File Format:  Gerber RS274X*
G04 File Origin:  Cadence Allegro 16.5-S039*
G04 Origin Date:  Fri Nov 22 15:27:02 2013*
G04 *
G04 Layer:  VIA CLASS/PASTEMASK_TOP*
G04 Layer:  PIN/PASTEMASK_TOP*
G04 Layer:  PACKAGE GEOMETRY/PASTEMASK_TOP*
G04 Layer:  DRAWING FORMAT/LAYER_PCB_STORY*
G04 Layer:  DRAWING FORMAT/LAYER_PAST_T*
G04 Layer:  BOARD GEOMETRY/PANEL_OUTLINE*
G04 *
G04 Offset:    (0.00 0.00)*
G04 Mirror:    No*
G04 Mode:      Positive*
G04 Rotation:  0*
G04 FullContactRelief:  No*
G04 UndefLineWidth:     6.00*
G04 ================== end FILE IDENTIFICATION RECORD ====================*
%FSLAX35Y35*MOIN*%
%IR0*IPPOS*OFA0.00000B0.00000*MIA0B0*SFA1.00000B1.00000*%
%ADD10C,.02*%
%ADD11C,.006*%
G75*
%LPD*%
G75*
G54D10*
G01X-67189Y-77263D02*
G02I-12000J0D01*
G01X-72339D02*
G02I-6850J0D01*
G01X-79189Y-93263D02*
Y-61263D01*
G01X-63189Y-77263D02*
X-95189D01*
G01X-63189Y-93263D02*
Y-173263D01*
G01D02*
X1156611D01*
G01X-63189Y-93263D02*
X1156611D01*
G01X-63189Y-128763D02*
X1156611D01*
G01X369111Y-93263D02*
Y-173263D01*
G01X506611Y-93263D02*
Y-173263D01*
G01X621611Y-93263D02*
Y-173263D01*
G01X789111Y-93263D02*
Y-173263D01*
G01X959111Y-93263D02*
Y-173263D01*
G01X1156611Y-93263D02*
Y-173263D01*
G01X1184611Y-77263D02*
G02I-12000J0D01*
G01X1179461D02*
G02I-6850J0D01*
G01X1172611Y-93263D02*
Y-61263D01*
G01X1188611Y-77263D02*
X1156611D01*
G54D11*
G01X-44374Y-163263D02*
Y-145763D01*
G01X-35204D02*
Y-163263D01*
G01Y-154513D02*
X-44374D01*
G01X-22289Y-163263D02*
X-23599Y-162971D01*
X-24909Y-161805D01*
X-25783Y-159763D01*
X-26219Y-157430D01*
X-25783Y-155096D01*
X-24909Y-153055D01*
X-23599Y-151888D01*
X-22289Y-151597D01*
X-20979Y-151888D01*
X-19669Y-153055D01*
X-18796Y-155096D01*
X-18577Y-157430D01*
X-18796Y-159763D01*
X-19669Y-161805D01*
X-20979Y-162971D01*
X-22289Y-163263D01*
G01X-8501D02*
Y-151597D01*
G01Y-154513D02*
X-7627Y-153055D01*
X-6317Y-151888D01*
X-4571Y-151597D01*
X-3043Y-151888D01*
X-1732Y-153055D01*
X-1077Y-155096D01*
Y-163263D01*
G01X9436Y-155388D02*
X16423D01*
X15768Y-153346D01*
X14676Y-152180D01*
X13148Y-151597D01*
X11619Y-151888D01*
X10309Y-152763D01*
X9436Y-154805D01*
X8999Y-156555D01*
Y-158305D01*
X9436Y-160055D01*
X10528Y-161805D01*
X11838Y-162971D01*
X13366Y-163263D01*
X14894Y-162680D01*
X16423Y-160930D01*
G01X25626Y-168513D02*
X26936Y-169096D01*
X28683Y-168513D01*
X29774Y-167347D01*
X30648Y-165888D01*
X31957Y-161222D01*
X34796Y-151597D01*
G01X27809D02*
X31957Y-161222D01*
G01X66957Y-153930D02*
X67831Y-153055D01*
X68486Y-151597D01*
X68923Y-149554D01*
X68486Y-147805D01*
X67613Y-146638D01*
X66084Y-145763D01*
X60189D01*
Y-163263D01*
X67394D01*
X68923Y-162097D01*
X69796Y-160346D01*
X70233Y-158305D01*
X69796Y-156263D01*
X68486Y-154513D01*
X66957Y-153930D01*
X60189D01*
G01X86641Y-163263D02*
Y-151597D01*
G01Y-153638D02*
X85768Y-152472D01*
X84457Y-151888D01*
X82929Y-151597D01*
X81401Y-152180D01*
X80091Y-153346D01*
X79217Y-155096D01*
X78781Y-157430D01*
X79217Y-159763D01*
X80091Y-161513D01*
X81401Y-162680D01*
X82929Y-163263D01*
X84457Y-162971D01*
X85768Y-162097D01*
X86641Y-160930D01*
G01X104141Y-145763D02*
Y-163263D01*
G01Y-160639D02*
X103268Y-162097D01*
X101957Y-162971D01*
X100429Y-163263D01*
X98683Y-162680D01*
X97373Y-161222D01*
X96499Y-159472D01*
X96281Y-157430D01*
X96499Y-155388D01*
X97373Y-153638D01*
X98683Y-152180D01*
X100429Y-151597D01*
X101957Y-151888D01*
X103049Y-152472D01*
X104141Y-153638D01*
G01X114654Y-167638D02*
X116183Y-168805D01*
X117929Y-169096D01*
X119457Y-168805D01*
X120768Y-167347D01*
X121641Y-165305D01*
Y-151597D01*
G01Y-153930D02*
X120768Y-152763D01*
X119457Y-151888D01*
X117929Y-151597D01*
X116183Y-152180D01*
X115091Y-153346D01*
X114217Y-155388D01*
X113781Y-157430D01*
X113999Y-159180D01*
X114873Y-161222D01*
X116183Y-162680D01*
X117929Y-163263D01*
X119239Y-162971D01*
X120768Y-161805D01*
X121641Y-160639D01*
G01X131936Y-155388D02*
X138923D01*
X138268Y-153346D01*
X137176Y-152180D01*
X135648Y-151597D01*
X134119Y-151888D01*
X132809Y-152763D01*
X131936Y-154805D01*
X131499Y-156555D01*
Y-158305D01*
X131936Y-160055D01*
X133028Y-161805D01*
X134338Y-162971D01*
X135866Y-163263D01*
X137394Y-162680D01*
X138923Y-160930D01*
G01X149654Y-163263D02*
Y-151597D01*
G01Y-153930D02*
X150746Y-152763D01*
X151838Y-151888D01*
X153366Y-151597D01*
X154457Y-151888D01*
X155768Y-152763D01*
G01X183344Y-163263D02*
Y-145763D01*
X188803D01*
X190549Y-146638D01*
X191641Y-147805D01*
X192078Y-150138D01*
X191641Y-152472D01*
X190331Y-153930D01*
X188803Y-154805D01*
X183344D01*
G01X188803D02*
X192078Y-163263D01*
G01X205211Y-151597D02*
Y-163263D01*
G01Y-146930D02*
X204774Y-146638D01*
Y-146055D01*
X205211Y-145763D01*
X205648Y-146055D01*
Y-146638D01*
X205211Y-146930D01*
G01X219436Y-161222D02*
X220528Y-162388D01*
X222056Y-163263D01*
X223366D01*
X224676Y-162680D01*
X225549Y-161805D01*
X225986Y-160639D01*
X225768Y-158888D01*
X224894Y-158013D01*
X220964Y-156263D01*
X220091Y-154221D01*
X220528Y-152763D01*
X221401Y-151888D01*
X222711Y-151597D01*
X224021Y-151888D01*
X225331Y-152763D01*
G01X236936Y-155388D02*
X243923D01*
X243268Y-153346D01*
X242176Y-152180D01*
X240648Y-151597D01*
X239119Y-151888D01*
X237809Y-152763D01*
X236936Y-154805D01*
X236499Y-156555D01*
Y-158305D01*
X236936Y-160055D01*
X238028Y-161805D01*
X239338Y-162971D01*
X240866Y-163263D01*
X242394Y-162680D01*
X243923Y-160930D01*
G01X254654Y-163263D02*
Y-151597D01*
G01Y-153930D02*
X255746Y-152763D01*
X256838Y-151888D01*
X258366Y-151597D01*
X259457Y-151888D01*
X260768Y-152763D01*
G01X297514Y-147222D02*
X296204Y-146346D01*
X294676Y-145763D01*
X292929D01*
X290964Y-146638D01*
X289436Y-148096D01*
X288344Y-149847D01*
X287471Y-152763D01*
X287252Y-155388D01*
X287689Y-158013D01*
X288344Y-159763D01*
X289654Y-161513D01*
X291183Y-162680D01*
X292711Y-163263D01*
X294239D01*
X295768Y-162680D01*
X297078Y-161805D01*
X298170Y-160639D01*
G01X314141Y-163263D02*
Y-151597D01*
G01Y-153638D02*
X313268Y-152472D01*
X311957Y-151888D01*
X310429Y-151597D01*
X308901Y-152180D01*
X307591Y-153346D01*
X306717Y-155096D01*
X306281Y-157430D01*
X306717Y-159763D01*
X307591Y-161513D01*
X308901Y-162680D01*
X310429Y-163263D01*
X311957Y-162971D01*
X313268Y-162097D01*
X314141Y-160930D01*
G01X324654Y-163263D02*
Y-151597D01*
G01Y-153930D02*
X325746Y-152763D01*
X326838Y-151888D01*
X328366Y-151597D01*
X329457Y-151888D01*
X330768Y-152763D01*
G01X349141Y-145763D02*
Y-163263D01*
G01Y-160639D02*
X348268Y-162097D01*
X346957Y-162971D01*
X345429Y-163263D01*
X343683Y-162680D01*
X342373Y-161222D01*
X341499Y-159472D01*
X341281Y-157430D01*
X341499Y-155388D01*
X342373Y-153638D01*
X343683Y-152180D01*
X345429Y-151597D01*
X346957Y-151888D01*
X348049Y-152472D01*
X349141Y-153638D01*
G01X112034Y-118263D02*
Y-100763D01*
X117711Y-115346D01*
X123388Y-100763D01*
Y-118263D01*
G01X135211D02*
X133901Y-117971D01*
X132591Y-116805D01*
X131717Y-114763D01*
X131281Y-112430D01*
X131717Y-110096D01*
X132591Y-108055D01*
X133901Y-106888D01*
X135211Y-106597D01*
X136521Y-106888D01*
X137831Y-108055D01*
X138704Y-110096D01*
X138923Y-112430D01*
X138704Y-114763D01*
X137831Y-116805D01*
X136521Y-117971D01*
X135211Y-118263D01*
G01X156641Y-100763D02*
Y-118263D01*
G01Y-115639D02*
X155768Y-117097D01*
X154457Y-117971D01*
X152929Y-118263D01*
X151183Y-117680D01*
X149873Y-116222D01*
X148999Y-114472D01*
X148781Y-112430D01*
X148999Y-110388D01*
X149873Y-108638D01*
X151183Y-107180D01*
X152929Y-106597D01*
X154457Y-106888D01*
X155549Y-107472D01*
X156641Y-108638D01*
G01X166936Y-110388D02*
X173923D01*
X173268Y-108346D01*
X172176Y-107180D01*
X170648Y-106597D01*
X169119Y-106888D01*
X167809Y-107763D01*
X166936Y-109805D01*
X166499Y-111555D01*
Y-113305D01*
X166936Y-115055D01*
X168028Y-116805D01*
X169338Y-117971D01*
X170866Y-118263D01*
X172394Y-117680D01*
X173923Y-115930D01*
G01X187711Y-118263D02*
Y-100763D01*
G01X402811Y-163263D02*
Y-145763D01*
X400191Y-149263D01*
G01Y-163263D02*
X405431D01*
G01X415508Y-159763D02*
X416817Y-161805D01*
X418564Y-162971D01*
X420529Y-163263D01*
X422276Y-162971D01*
X424023Y-161513D01*
X425114Y-159763D01*
X425333Y-158013D01*
X424896Y-155972D01*
X423368Y-154513D01*
X421839Y-153930D01*
X419874D01*
G01X421839D02*
X423149Y-153055D01*
X424241Y-151597D01*
X424678Y-149847D01*
X424241Y-148096D01*
X423149Y-146638D01*
X421184Y-145763D01*
X419219Y-146055D01*
X417254Y-147222D01*
G01X434099Y-161222D02*
X435628Y-162680D01*
X437374Y-163263D01*
X439121Y-162680D01*
X440649Y-160930D01*
X441741Y-158305D01*
X442178Y-155680D01*
Y-152472D01*
X441741Y-149847D01*
X440649Y-147513D01*
X439339Y-146346D01*
X437811Y-145763D01*
X436064Y-146346D01*
X434754Y-147513D01*
X433881Y-149263D01*
X433444Y-151597D01*
X433881Y-153638D01*
X434973Y-155680D01*
X436283Y-156847D01*
X437811Y-157138D01*
X439557Y-156555D01*
X440868Y-155096D01*
X442178Y-152472D01*
G01X455311Y-163263D02*
Y-145763D01*
X452691Y-149263D01*
G01Y-163263D02*
X457931D01*
G01X469099Y-161222D02*
X470628Y-162680D01*
X472374Y-163263D01*
X474121Y-162680D01*
X475649Y-160930D01*
X476741Y-158305D01*
X477178Y-155680D01*
Y-152472D01*
X476741Y-149847D01*
X475649Y-147513D01*
X474339Y-146346D01*
X472811Y-145763D01*
X471064Y-146346D01*
X469754Y-147513D01*
X468881Y-149263D01*
X468444Y-151597D01*
X468881Y-153638D01*
X469973Y-155680D01*
X471283Y-156847D01*
X472811Y-157138D01*
X474557Y-156555D01*
X475868Y-155096D01*
X477178Y-152472D01*
G01X389694Y-118263D02*
Y-100763D01*
X394934D01*
X396681Y-101638D01*
X397991Y-103680D01*
X398428Y-106013D01*
X397991Y-108346D01*
X396899Y-110096D01*
X394934Y-110972D01*
X389694D01*
G01X416364Y-102222D02*
X415054Y-101346D01*
X413526Y-100763D01*
X411779D01*
X409814Y-101638D01*
X408286Y-103096D01*
X407194Y-104847D01*
X406321Y-107763D01*
X406102Y-110388D01*
X406539Y-113013D01*
X407194Y-114763D01*
X408504Y-116513D01*
X410033Y-117680D01*
X411561Y-118263D01*
X413089D01*
X414618Y-117680D01*
X415928Y-116805D01*
X417020Y-115639D01*
G01X430807Y-108930D02*
X431681Y-108055D01*
X432336Y-106597D01*
X432773Y-104554D01*
X432336Y-102805D01*
X431463Y-101638D01*
X429934Y-100763D01*
X424039D01*
Y-118263D01*
X431244D01*
X432773Y-117097D01*
X433646Y-115346D01*
X434083Y-113305D01*
X433646Y-111263D01*
X432336Y-109513D01*
X430807Y-108930D01*
X424039D01*
G01X440011Y-124096D02*
X453111D01*
G01X459039Y-118263D02*
Y-100763D01*
X469083Y-118263D01*
Y-100763D01*
G01X481561Y-118263D02*
X479814Y-117971D01*
X478286Y-116805D01*
X476976Y-115055D01*
X476102Y-113013D01*
X475666Y-110680D01*
Y-108346D01*
X476102Y-106013D01*
X476976Y-103971D01*
X478286Y-102222D01*
X479814Y-101055D01*
X481561Y-100763D01*
X483307Y-101055D01*
X484836Y-102222D01*
X486146Y-103971D01*
X487020Y-106013D01*
X487456Y-108346D01*
Y-110680D01*
X487020Y-113013D01*
X486146Y-115055D01*
X484836Y-116805D01*
X483307Y-117971D01*
X481561Y-118263D01*
G01X532402Y-100763D02*
X537861Y-118263D01*
X543320Y-100763D01*
G01X559728Y-118263D02*
X550994D01*
Y-100763D01*
X559728D01*
G01X556234Y-109221D02*
X550994D01*
G01X568494Y-118263D02*
Y-100763D01*
X573953D01*
X575699Y-101638D01*
X576791Y-102805D01*
X577228Y-105138D01*
X576791Y-107472D01*
X575481Y-108930D01*
X573953Y-109805D01*
X568494D01*
G01X573953D02*
X577228Y-118263D01*
G01X590361Y-118846D02*
X589924Y-118555D01*
Y-117971D01*
X590361Y-117680D01*
X590798Y-117971D01*
Y-118555D01*
X590361Y-118846D01*
G01X550776Y-160930D02*
X552523Y-162388D01*
X554488Y-163263D01*
X556234D01*
X557981Y-162388D01*
X559291Y-160930D01*
X559946Y-158888D01*
X559509Y-156847D01*
X558418Y-155096D01*
X556453Y-153930D01*
X553833Y-153346D01*
X552304Y-152180D01*
X551649Y-150138D01*
X552086Y-148096D01*
X553178Y-146638D01*
X554706Y-145763D01*
X556234D01*
X557763Y-146346D01*
X559073Y-147805D01*
G01X567402Y-163263D02*
X572861Y-145763D01*
X578320Y-163263D01*
G01X576354Y-157138D02*
X569367D01*
G01X679061Y-145763D02*
Y-163263D01*
G01X674039Y-145763D02*
X684083D01*
G01X691976Y-160930D02*
X693723Y-162388D01*
X695688Y-163263D01*
X697434D01*
X699181Y-162388D01*
X700491Y-160930D01*
X701146Y-158888D01*
X700709Y-156847D01*
X699618Y-155096D01*
X697653Y-153930D01*
X695033Y-153346D01*
X693504Y-152180D01*
X692849Y-150138D01*
X693286Y-148096D01*
X694378Y-146638D01*
X695906Y-145763D01*
X697434D01*
X698963Y-146346D01*
X700273Y-147805D01*
G01X708384Y-163263D02*
Y-145763D01*
X714061Y-160346D01*
X719738Y-145763D01*
Y-163263D01*
G01X726758D02*
Y-145763D01*
X731124D01*
X732871Y-146638D01*
X734181Y-147805D01*
X735273Y-149554D01*
X736146Y-151597D01*
X736364Y-154513D01*
X736146Y-157430D01*
X735273Y-159472D01*
X734181Y-161222D01*
X732871Y-162388D01*
X731124Y-163263D01*
X726758D01*
G01X665944Y-100763D02*
Y-118263D01*
X674678D01*
G01X691741D02*
Y-106597D01*
G01Y-108638D02*
X690868Y-107472D01*
X689557Y-106888D01*
X688029Y-106597D01*
X686501Y-107180D01*
X685191Y-108346D01*
X684317Y-110096D01*
X683881Y-112430D01*
X684317Y-114763D01*
X685191Y-116513D01*
X686501Y-117680D01*
X688029Y-118263D01*
X689557Y-117971D01*
X690868Y-117097D01*
X691741Y-115930D01*
G01X700726Y-123513D02*
X702036Y-124096D01*
X703783Y-123513D01*
X704874Y-122347D01*
X705748Y-120888D01*
X707057Y-116222D01*
X709896Y-106597D01*
G01X702909D02*
X707057Y-116222D01*
G01X719536Y-110388D02*
X726523D01*
X725868Y-108346D01*
X724776Y-107180D01*
X723248Y-106597D01*
X721719Y-106888D01*
X720409Y-107763D01*
X719536Y-109805D01*
X719099Y-111555D01*
Y-113305D01*
X719536Y-115055D01*
X720628Y-116805D01*
X721938Y-117971D01*
X723466Y-118263D01*
X724994Y-117680D01*
X726523Y-115930D01*
G01X737254Y-118263D02*
Y-106597D01*
G01Y-108930D02*
X738346Y-107763D01*
X739438Y-106888D01*
X740966Y-106597D01*
X742057Y-106888D01*
X743368Y-107763D01*
G01X808058Y-118263D02*
Y-100763D01*
X812424D01*
X814171Y-101638D01*
X815481Y-102805D01*
X816573Y-104554D01*
X817446Y-106597D01*
X817664Y-109513D01*
X817446Y-112430D01*
X816573Y-114472D01*
X815481Y-116222D01*
X814171Y-117388D01*
X812424Y-118263D01*
X808058D01*
G01X827086Y-110388D02*
X834073D01*
X833418Y-108346D01*
X832326Y-107180D01*
X830798Y-106597D01*
X829269Y-106888D01*
X827959Y-107763D01*
X827086Y-109805D01*
X826649Y-111555D01*
Y-113305D01*
X827086Y-115055D01*
X828178Y-116805D01*
X829488Y-117971D01*
X831016Y-118263D01*
X832544Y-117680D01*
X834073Y-115930D01*
G01X844586Y-116222D02*
X845678Y-117388D01*
X847206Y-118263D01*
X848516D01*
X849826Y-117680D01*
X850699Y-116805D01*
X851136Y-115639D01*
X850918Y-113888D01*
X850044Y-113013D01*
X846114Y-111263D01*
X845241Y-109221D01*
X845678Y-107763D01*
X846551Y-106888D01*
X847861Y-106597D01*
X849171Y-106888D01*
X850481Y-107763D01*
G01X865361Y-106597D02*
Y-118263D01*
G01Y-101930D02*
X864924Y-101638D01*
Y-101055D01*
X865361Y-100763D01*
X865798Y-101055D01*
Y-101638D01*
X865361Y-101930D01*
G01X879804Y-122638D02*
X881333Y-123805D01*
X883079Y-124096D01*
X884607Y-123805D01*
X885918Y-122347D01*
X886791Y-120305D01*
Y-106597D01*
G01Y-108930D02*
X885918Y-107763D01*
X884607Y-106888D01*
X883079Y-106597D01*
X881333Y-107180D01*
X880241Y-108346D01*
X879367Y-110388D01*
X878931Y-112430D01*
X879149Y-114180D01*
X880023Y-116222D01*
X881333Y-117680D01*
X883079Y-118263D01*
X884389Y-117971D01*
X885918Y-116805D01*
X886791Y-115639D01*
G01X896649Y-118263D02*
Y-106597D01*
G01Y-109513D02*
X897523Y-108055D01*
X898833Y-106888D01*
X900579Y-106597D01*
X902107Y-106888D01*
X903418Y-108055D01*
X904073Y-110096D01*
Y-118263D01*
G01X914586Y-110388D02*
X921573D01*
X920918Y-108346D01*
X919826Y-107180D01*
X918298Y-106597D01*
X916769Y-106888D01*
X915459Y-107763D01*
X914586Y-109805D01*
X914149Y-111555D01*
Y-113305D01*
X914586Y-115055D01*
X915678Y-116805D01*
X916988Y-117971D01*
X918516Y-118263D01*
X920044Y-117680D01*
X921573Y-115930D01*
G01X932304Y-118263D02*
Y-106597D01*
G01Y-108930D02*
X933396Y-107763D01*
X934488Y-106888D01*
X936016Y-106597D01*
X937107Y-106888D01*
X938418Y-107763D01*
G01X853991Y-145763D02*
X859231D01*
G01X856611D02*
Y-163263D01*
G01X853991D02*
X859231D01*
G01X868652Y-145763D02*
X874111Y-163263D01*
X879570Y-145763D01*
G01X891611Y-163263D02*
Y-155388D01*
X887244Y-145763D01*
G01X895978D02*
X891611Y-155388D01*
G01X979061Y-163263D02*
Y-145763D01*
X976441Y-149263D01*
G01Y-163263D02*
X981681D01*
G01X996561D02*
Y-145763D01*
X993941Y-149263D01*
G01Y-163263D02*
X999181D01*
G01X1010131Y-163846D02*
X1017991Y-145763D01*
G01X1027413Y-148680D02*
X1028723Y-146930D01*
X1030251Y-146055D01*
X1031998Y-145763D01*
X1034181Y-146346D01*
X1035709Y-147805D01*
X1036146Y-149554D01*
X1035928Y-151305D01*
X1035054Y-152763D01*
X1030688Y-155680D01*
X1028723Y-157721D01*
X1027413Y-160639D01*
X1026976Y-163263D01*
X1036146D01*
G01X1044913Y-148680D02*
X1046223Y-146930D01*
X1047751Y-146055D01*
X1049498Y-145763D01*
X1051681Y-146346D01*
X1053209Y-147805D01*
X1053646Y-149554D01*
X1053428Y-151305D01*
X1052554Y-152763D01*
X1048188Y-155680D01*
X1046223Y-157721D01*
X1044913Y-160639D01*
X1044476Y-163263D01*
X1053646D01*
G01X1062631Y-163846D02*
X1070491Y-145763D01*
G01X1079913Y-148680D02*
X1081223Y-146930D01*
X1082751Y-146055D01*
X1084498Y-145763D01*
X1086681Y-146346D01*
X1088209Y-147805D01*
X1088646Y-149554D01*
X1088428Y-151305D01*
X1087554Y-152763D01*
X1083188Y-155680D01*
X1081223Y-157721D01*
X1079913Y-160639D01*
X1079476Y-163263D01*
X1088646D01*
G01X1101561Y-145763D02*
X1099814Y-146346D01*
X1098504Y-147805D01*
X1097631Y-149554D01*
X1096976Y-151888D01*
X1096758Y-154513D01*
X1096976Y-157138D01*
X1097631Y-159472D01*
X1098504Y-161222D01*
X1099814Y-162680D01*
X1101561Y-163263D01*
X1103307Y-162680D01*
X1104618Y-161222D01*
X1105491Y-159472D01*
X1106146Y-157138D01*
X1106364Y-154513D01*
X1106146Y-151888D01*
X1105491Y-149554D01*
X1104618Y-147805D01*
X1103307Y-146346D01*
X1101561Y-145763D01*
G01X1119061Y-163263D02*
Y-145763D01*
X1116441Y-149263D01*
G01Y-163263D02*
X1121681D01*
G01X1131758Y-159763D02*
X1133067Y-161805D01*
X1134814Y-162971D01*
X1136779Y-163263D01*
X1138526Y-162971D01*
X1140273Y-161513D01*
X1141364Y-159763D01*
X1141583Y-158013D01*
X1141146Y-155972D01*
X1139618Y-154513D01*
X1138089Y-153930D01*
X1136124D01*
G01X1138089D02*
X1139399Y-153055D01*
X1140491Y-151597D01*
X1140928Y-149847D01*
X1140491Y-148096D01*
X1139399Y-146638D01*
X1137434Y-145763D01*
X1135469Y-146055D01*
X1133504Y-147222D01*
G01X1026758Y-118263D02*
Y-100763D01*
X1031124D01*
X1032871Y-101638D01*
X1034181Y-102805D01*
X1035273Y-104554D01*
X1036146Y-106597D01*
X1036364Y-109513D01*
X1036146Y-112430D01*
X1035273Y-114472D01*
X1034181Y-116222D01*
X1032871Y-117388D01*
X1031124Y-118263D01*
X1026758D01*
G01X1052991D02*
Y-106597D01*
G01Y-108638D02*
X1052118Y-107472D01*
X1050807Y-106888D01*
X1049279Y-106597D01*
X1047751Y-107180D01*
X1046441Y-108346D01*
X1045567Y-110096D01*
X1045131Y-112430D01*
X1045567Y-114763D01*
X1046441Y-116513D01*
X1047751Y-117680D01*
X1049279Y-118263D01*
X1050807Y-117971D01*
X1052118Y-117097D01*
X1052991Y-115930D01*
G01X1066561Y-100763D02*
Y-118263D01*
G01X1063504Y-106597D02*
X1069618D01*
G01X1080786Y-110388D02*
X1087773D01*
X1087118Y-108346D01*
X1086026Y-107180D01*
X1084498Y-106597D01*
X1082969Y-106888D01*
X1081659Y-107763D01*
X1080786Y-109805D01*
X1080349Y-111555D01*
Y-113305D01*
X1080786Y-115055D01*
X1081878Y-116805D01*
X1083188Y-117971D01*
X1084716Y-118263D01*
X1086244Y-117680D01*
X1087773Y-115930D01*
G01X-20271Y15000D02*
Y676339D01*
G01Y15000D02*
G03X-5271Y0I15000J0D01*
G01Y691339D02*
G03X-20271Y676339I0J-15000D01*
G01X0Y37795D02*
G03X3937Y33858I3937J0D01*
G01X21063Y29921D02*
G03X17126Y33858I-3937J0D01*
G01X3937D02*
X17126D01*
G01X299409Y0D02*
X23031D01*
G01X21063Y1969D02*
X23031Y0D01*
G01X21063Y1969D02*
Y29921D01*
G01X0Y102756D02*
Y37795D01*
G01D02*
G03X-7874I-3937J0D01*
G01X3937Y25984D02*
X13189D01*
G01X-7874Y37795D02*
G03X3937Y25984I11811J0D01*
G01X13189Y0D02*
X-5271D01*
G01X13189Y25984D02*
Y0D01*
G01X3937Y106693D02*
G03X0Y102756I0J-3937D01*
G01X-7874Y68504D02*
G03X0I3937J0D01*
G01X-7874D02*
Y122737D01*
G01X0Y118504D02*
G03X3937Y114567I3937J0D01*
G01Y157382D02*
G03X0Y153445I0J-3937D01*
G01X17126Y157382D02*
G03X21063Y161319I0J3937D01*
G01X0Y118504D02*
Y153445D01*
G01X21063Y219292D02*
Y161319D01*
G01D02*
Y187402D01*
G01X143701Y114567D02*
X3937D01*
G01Y157382D02*
X17126D01*
G01X3937Y106693D02*
X143701D01*
G01X-7874Y153445D02*
Y157382D01*
G01Y153445D02*
G03X0I3937J0D01*
G01Y122737D02*
G03X-7874I-3937J0D01*
G01X-10433Y161070D02*
G03X-7874Y157382I3937J0D01*
G01X-10433Y265210D02*
Y161070D01*
G01X51378Y181496D02*
G03X47441Y177559I0J-3937D01*
G01Y165748D02*
G03X51378Y161811I3937J0D01*
G01X47441Y165748D02*
Y177559D01*
G01X23031Y221260D02*
X21063Y219292D01*
G01X23031Y221260D02*
X63189D01*
G01X0Y272835D02*
G03X3937Y268898I3937J0D01*
G01X21063Y264961D02*
G03X17126Y268898I-3937J0D01*
G01X3937D02*
X17126D01*
G01X299409Y235040D02*
X23031D01*
G01X21063Y237008D02*
X23031Y235040D01*
G01X21063Y237008D02*
Y264961D01*
G01X0Y337796D02*
Y272835D01*
G01D02*
G03X-7874I-3937J0D01*
G01Y268898D02*
G03X-10433Y265210I1378J-3688D01*
G01X-7874Y268898D02*
Y272835D01*
G01X3937Y341733D02*
G03X0Y337796I0J-3937D01*
G01X3937Y341733D02*
X143701D01*
G01X-7874Y303543D02*
Y357781D01*
G01Y303544D02*
G03X0I3937J0D01*
G01X47441Y400788D02*
G03X51378Y396851I3937J0D01*
G01X47441Y400788D02*
Y412599D01*
G01X0Y353544D02*
G03X3937Y349607I3937J0D01*
G01Y392422D02*
G03X0Y388485I0J-3937D01*
G01X17126Y392422D02*
G03X21063Y396359I0J3937D01*
G01X0Y353544D02*
Y388485D01*
G01X21063Y454331D02*
Y396359D01*
G01D02*
Y422441D01*
G01X143701Y349607D02*
X3937D01*
G01Y392422D02*
X17126D01*
G01X-7874Y388480D02*
Y392422D01*
G01Y388485D02*
G03X0I3937J0D01*
G01Y357776D02*
G03X-7874I-3937J0D01*
G01X-10433Y396110D02*
G03X-7874Y392422I3937J0D01*
G01X-10433Y500250D02*
Y396110D01*
G01X51378Y416536D02*
G03X47441Y412599I0J-3937D01*
G01X23031Y456300D02*
X21063Y454331D01*
G01X23031Y456300D02*
X63189D01*
G01X0Y507874D02*
G03X3937Y503937I3937J0D01*
G01X21063Y500000D02*
G03X17126Y503937I-3937J0D01*
G01X3937D02*
X17126D01*
G01X299409Y470079D02*
X23031D01*
G01X21063Y472048D02*
X23031Y470079D01*
G01X21063Y472048D02*
Y500000D01*
G01X0Y572835D02*
Y507874D01*
G01D02*
G03X-7874I-3937J0D01*
G01Y503937D02*
Y507880D01*
G01Y503937D02*
G03X-10433Y500250I1378J-3688D01*
G01X3937Y576772D02*
G03X0Y572835I0J-3937D01*
G01X3937Y576772D02*
X143701D01*
G01X0Y588583D02*
G03X3937Y584646I3937J0D01*
G01X0Y588583D02*
Y623524D01*
G01X143701Y584646D02*
X3937D01*
G01X-7874Y538578D02*
Y592823D01*
G01Y538583D02*
G03X0I3937J0D01*
G01X51378Y651576D02*
G03X47441Y647639I0J-3937D01*
G01Y635828D02*
G03X51378Y631891I3937J0D01*
G01X47441Y635828D02*
Y647639D01*
G01X3937Y627461D02*
G03X0Y623524I0J-3937D01*
G01X17126Y627461D02*
G03X21063Y631398I0J3937D01*
G01Y689371D02*
Y631398D01*
G01D02*
Y657481D01*
G01X3937Y627461D02*
X17126D01*
G01X1830Y651994D02*
G03I-4292J0D01*
G01X-7874Y623517D02*
Y623536D01*
G01X13189Y691339D02*
Y635335D01*
G01X3937D02*
X13189D01*
G01X3937D02*
G03X-7874Y623524I0J-11811D01*
G01D02*
G03X0I3937J0D01*
G01Y592816D02*
G03X-7874I-3937J0D01*
G01X23031Y691339D02*
X21063Y689371D01*
G01X23031Y691339D02*
X63189D01*
G01X13189D02*
X-5271D01*
G01X63189Y161811D02*
G03X67126Y165748I0J3937D01*
G01X73425D02*
G03X77362Y161811I3937J0D01*
G01X89173D02*
G03X93110Y165748I0J3937D01*
G01X99409D02*
G03X103346Y161811I3937J0D01*
G01X63189D02*
X51378D01*
G01X89173D02*
X77362D01*
G01X115157D02*
X103346D01*
G01X89173Y114567D02*
G03Y106693I0J-3937D01*
G01X58465D02*
G03Y114567I0J3937D01*
G01X67126Y177559D02*
G03X63189Y181496I-3937J0D01*
G01X77362D02*
G03X73425Y177559I0J-3937D01*
G01X93110D02*
G03X89173Y181496I-3937J0D01*
G01X103346D02*
G03X99409Y177559I0J-3937D01*
G01X67126D02*
Y165748D01*
G01X73425D02*
Y177559D01*
G01X93110D02*
Y165748D01*
G01X99409D02*
Y177559D01*
G01X103346Y181496D02*
X115157D01*
G01X77362D02*
X89173D01*
G01X51378D02*
X63189D01*
G01X65157Y191930D02*
G03X72638I3740J0D01*
G01X65157Y219292D02*
Y191930D01*
G01X74606Y221260D02*
X72638Y219292D01*
G01D02*
Y191930D01*
G01X65157Y219292D02*
X63189Y221260D01*
G01X74606D02*
X350984D01*
G01X89173Y349607D02*
G03Y341733I0J-3937D01*
G01X58465D02*
G03Y349607I0J3937D01*
G01X63189Y396851D02*
G03X67126Y400788I0J3937D01*
G01X73425D02*
G03X77362Y396851I3937J0D01*
G01X89173D02*
G03X93110Y400788I0J3937D01*
G01X99409D02*
G03X103346Y396851I3937J0D01*
G01X67126Y412599D02*
Y400788D01*
G01X73425D02*
Y412599D01*
G01X93110D02*
Y400788D01*
G01X99409D02*
Y412599D01*
G01X63189Y396851D02*
X51378D01*
G01X89173D02*
X77362D01*
G01X115157D02*
X103346D01*
G01X67126Y412599D02*
G03X63189Y416536I-3937J0D01*
G01X77362D02*
G03X73425Y412599I0J-3937D01*
G01X93110D02*
G03X89173Y416536I-3937J0D01*
G01X103346D02*
G03X99409Y412599I0J-3937D01*
G01X103346Y416536D02*
X115157D01*
G01X77362D02*
X89173D01*
G01X51378D02*
X63189D01*
G01X65157Y426969D02*
G03X72638I3740J0D01*
G01X65157Y454331D02*
Y426969D01*
G01X74606Y456300D02*
X72638Y454331D01*
G01D02*
Y426969D01*
G01X65157Y454331D02*
X63189Y456300D01*
G01X74606D02*
X350984D01*
G01X89173Y584646D02*
G03Y576772I0J-3937D01*
G01X58465D02*
G03Y584646I0J3937D01*
G01X67126Y647639D02*
G03X63189Y651576I-3937J0D01*
G01Y631891D02*
G03X67126Y635828I0J3937D01*
G01X73425D02*
G03X77362Y631891I3937J0D01*
G01Y651576D02*
G03X73425Y647639I0J-3937D01*
G01X93110D02*
G03X89173Y651576I-3937J0D01*
G01Y631891D02*
G03X93110Y635828I0J3937D01*
G01X103346Y651576D02*
G03X99409Y647639I0J-3937D01*
G01Y635828D02*
G03X103346Y631891I3937J0D01*
G01X67126Y647639D02*
Y635828D01*
G01X73425D02*
Y647639D01*
G01X93110D02*
Y635828D01*
G01X99409D02*
Y647639D01*
G01X63189Y631891D02*
X51378D01*
G01X89173D02*
X77362D01*
G01X115157D02*
X103346D01*
G01Y651576D02*
X115157D01*
G01X77362D02*
X89173D01*
G01X51378D02*
X63189D01*
G01X65157Y662009D02*
G03X72638I3740J0D01*
G01X65157Y689371D02*
Y662009D01*
G01X74606Y691339D02*
X72638Y689371D01*
G01D02*
Y662009D01*
G01X65157Y689371D02*
X63189Y691339D01*
G01X74606D02*
X350984D01*
G01X147638Y102756D02*
G03X151575Y98819I3937J0D01*
G01X147638Y102756D02*
G03X143701Y106693I-3937J0D01*
G01X147638Y102756D02*
G03X151575Y98819I3937J0D01*
G01X147638Y102756D02*
G03X143701Y106693I-3937J0D01*
G01X147638Y102756D02*
G03X151575Y98819I3937J0D01*
G01X147638Y102756D02*
G03X143701Y106693I-3937J0D01*
G01X151575Y98819D02*
X222441D01*
G01X115157Y161811D02*
G03X119094Y165748I0J3937D01*
G01X151575Y122441D02*
G03X147638Y118504I0J-3937D01*
G01X143701Y114567D02*
G03X147638Y118504I0J3937D01*
G01X143701Y114567D02*
X112205D01*
G01X143701D02*
G03X147638Y118504I0J3937D01*
G01X151575Y122441D02*
G03X147638Y118504I0J-3937D01*
G01X151575Y122441D02*
G03X147638Y118504I0J-3937D01*
G01X143701Y114567D02*
G03X147638Y118504I0J3937D01*
G01X222441Y122441D02*
X151575D01*
G01X143701Y106693D02*
X112205D01*
G01X119094Y177559D02*
G03X115157Y181496I-3937J0D01*
G01X119094Y177559D02*
Y165748D01*
G01X147638Y337796D02*
G03X151575Y333859I3937J0D01*
G01X147638Y337796D02*
G03X143701Y341733I-3937J0D01*
G01D02*
X112205D01*
G01X147638Y337796D02*
G03X151575Y333859I3937J0D01*
G01X147638Y337796D02*
G03X143701Y341733I-3937J0D01*
G01X147638Y337796D02*
G03X151575Y333859I3937J0D01*
G01X147638Y337796D02*
G03X143701Y341733I-3937J0D01*
G01X151575Y333859D02*
X222441D01*
G01X115157Y396851D02*
G03X119094Y400788I0J3937D01*
G01Y412599D02*
Y400788D01*
G01X151575Y357481D02*
G03X147638Y353544I0J-3937D01*
G01X143701Y349607D02*
G03X147638Y353544I0J3937D01*
G01X143701Y349607D02*
X112205D01*
G01X143701D02*
G03X147638Y353544I0J3937D01*
G01X151575Y357481D02*
G03X147638Y353544I0J-3937D01*
G01X151575Y357481D02*
G03X147638Y353544I0J-3937D01*
G01X143701Y349607D02*
G03X147638Y353544I0J3937D01*
G01X222441Y357481D02*
X151575D01*
G01X119094Y412599D02*
G03X115157Y416536I-3937J0D01*
G01X147638Y572835D02*
G03X151575Y568898I3937J0D01*
G01X147638Y572835D02*
G03X143701Y576772I-3937J0D01*
G01D02*
X112205D01*
G01X147638Y572835D02*
G03X151575Y568898I3937J0D01*
G01X147638Y572835D02*
G03X143701Y576772I-3937J0D01*
G01X147638Y572835D02*
G03X151575Y568898I3937J0D01*
G01X147638Y572835D02*
G03X143701Y576772I-3937J0D01*
G01X151575Y568898D02*
X222441D01*
G01X151575Y592520D02*
G03X147638Y588583I0J-3937D01*
G01X143701Y584646D02*
G03X147638Y588583I0J3937D01*
G01X143701Y584646D02*
X112205D01*
G01X143701D02*
G03X147638Y588583I0J3937D01*
G01X151575Y592520D02*
G03X147638Y588583I0J-3937D01*
G01X151575Y592520D02*
G03X147638Y588583I0J-3937D01*
G01X143701Y584646D02*
G03X147638Y588583I0J3937D01*
G01X119094Y647639D02*
G03X115157Y651576I-3937J0D01*
G01Y631891D02*
G03X119094Y635828I0J3937D01*
G01Y647639D02*
Y635828D01*
G01X222441Y592520D02*
X151575D01*
G01X222441Y98819D02*
G03X226378Y102756I0J3937D01*
G01X230315Y106693D02*
G03X226378Y102756I0J-3937D01*
G01X230315Y106693D02*
G03X226378Y102756I0J-3937D01*
G01X222441Y98819D02*
G03X226378Y102756I0J3937D01*
G01X222441Y98819D02*
G03X226378Y102756I0J3937D01*
G01X230315Y106693D02*
G03X226378Y102756I0J-3937D01*
G01Y118504D02*
G03X222441Y122441I-3937J0D01*
G01X226378Y118504D02*
G03X230315Y114567I3937J0D01*
G01D02*
X261811D01*
G01X226378Y118504D02*
G03X222441Y122441I-3937J0D01*
G01X226378Y118504D02*
G03X230315Y114567I3937J0D01*
G01X226378Y118504D02*
G03X222441Y122441I-3937J0D01*
G01X226378Y118504D02*
G03X230315Y114567I3937J0D01*
G01X370079D02*
X230315D01*
G01Y106693D02*
X261811D01*
G01X230315D02*
X370079D01*
G01X222441Y333859D02*
G03X226378Y337796I0J3937D01*
G01X230315Y341733D02*
G03X226378Y337796I0J-3937D01*
G01X230315Y341733D02*
X261811D01*
G01X230315D02*
G03X226378Y337796I0J-3937D01*
G01X222441Y333859D02*
G03X226378Y337796I0J3937D01*
G01X222441Y333859D02*
G03X226378Y337796I0J3937D01*
G01X230315Y341733D02*
G03X226378Y337796I0J-3937D01*
G01X230315Y341733D02*
X370079D01*
G01X226378Y353544D02*
G03X222441Y357481I-3937J0D01*
G01X226378Y353544D02*
G03X230315Y349607I3937J0D01*
G01D02*
X261811D01*
G01X226378Y353544D02*
G03X222441Y357481I-3937J0D01*
G01X226378Y353544D02*
G03X230315Y349607I3937J0D01*
G01X226378Y353544D02*
G03X222441Y357481I-3937J0D01*
G01X226378Y353544D02*
G03X230315Y349607I3937J0D01*
G01X370079D02*
X230315D01*
G01X222441Y568898D02*
G03X226378Y572835I0J3937D01*
G01X230315Y576772D02*
G03X226378Y572835I0J-3937D01*
G01X230315Y576772D02*
X261811D01*
G01X230315D02*
G03X226378Y572835I0J-3937D01*
G01X222441Y568898D02*
G03X226378Y572835I0J3937D01*
G01X222441Y568898D02*
G03X226378Y572835I0J3937D01*
G01X230315Y576772D02*
G03X226378Y572835I0J-3937D01*
G01X230315Y576772D02*
X370079D01*
G01X226378Y588583D02*
G03X222441Y592520I-3937J0D01*
G01X226378Y588583D02*
G03X230315Y584646I3937J0D01*
G01D02*
X261811D01*
G01X226378Y588583D02*
G03X222441Y592520I-3937J0D01*
G01X226378Y588583D02*
G03X230315Y584646I3937J0D01*
G01X226378Y588583D02*
G03X222441Y592520I-3937J0D01*
G01X226378Y588583D02*
G03X230315Y584646I3937J0D01*
G01X370079D02*
X230315D01*
G01X280906Y43701D02*
G03X284843Y39764I3937J0D01*
G01X270669D02*
G03X274606Y43701I0J3937D01*
G01X254921D02*
G03X258858Y39764I3937J0D01*
G01X270669D02*
X258858D01*
G01X296654D02*
X284843D01*
G01Y59449D02*
G03X280906Y55512I0J-3937D01*
G01X258858Y59449D02*
G03X254921Y55512I0J-3937D01*
G01X274606D02*
G03X270669Y59449I-3937J0D01*
G01X280906Y43701D02*
Y55512D01*
G01X274606D02*
Y43701D01*
G01X254921D02*
Y55512D01*
G01X284843Y59449D02*
X296654D01*
G01X258858D02*
X270669D01*
G01X284843Y106693D02*
G03Y114567I0J3937D01*
G01X280906Y278741D02*
G03X284843Y274804I3937J0D01*
G01X270669D02*
G03X274606Y278741I0J3937D01*
G01X254921D02*
G03X258858Y274804I3937J0D01*
G01X280906Y278741D02*
Y290552D01*
G01X274606D02*
Y278741D01*
G01X254921D02*
Y290552D01*
G01X270669Y274804D02*
X258858D01*
G01X296654D02*
X284843D01*
G01Y294489D02*
G03X280906Y290552I0J-3937D01*
G01X258858Y294489D02*
G03X254921Y290552I0J-3937D01*
G01X274606D02*
G03X270669Y294489I-3937J0D01*
G01X284843D02*
X296654D01*
G01X258858D02*
X270669D01*
G01X284843Y341733D02*
G03Y349607I0J3937D01*
G01X280906Y513780D02*
G03X284843Y509843I3937J0D01*
G01Y529528D02*
G03X280906Y525591I0J-3937D01*
G01X270669Y509843D02*
G03X274606Y513780I0J3937D01*
G01X254921D02*
G03X258858Y509843I3937J0D01*
G01Y529528D02*
G03X254921Y525591I0J-3937D01*
G01X274606D02*
G03X270669Y529528I-3937J0D01*
G01X280906Y513780D02*
Y525591D01*
G01X274606D02*
Y513780D01*
G01X254921D02*
Y525591D01*
G01X284843Y529528D02*
X296654D01*
G01X258858D02*
X270669D01*
G01Y509843D02*
X258858D01*
G01X296654D02*
X284843D01*
G01Y576772D02*
G03Y584646I0J3937D01*
G01X322638Y39764D02*
G03X326575Y43701I0J3937D01*
G01X306890D02*
G03X310827Y39764I3937J0D01*
G01X296654D02*
G03X300591Y43701I0J3937D01*
G01X322638Y39764D02*
X310827D01*
G01X308858Y29331D02*
G03X301378I-3740J0D01*
G01X350984Y0D02*
X352953Y1969D01*
G01X308858D02*
Y29331D01*
G01X299409Y0D02*
X301378Y1969D01*
G01D02*
Y29331D01*
G01X308858Y1969D02*
X310827Y0D01*
G01X350984D02*
X310827D01*
G01Y59449D02*
G03X306890Y55512I0J-3937D01*
G01X326575D02*
G03X322638Y59449I-3937J0D01*
G01X300591Y55512D02*
G03X296654Y59449I-3937J0D01*
G01X326575Y55512D02*
Y43701D01*
G01X306890D02*
Y55512D01*
G01X300591D02*
Y43701D01*
G01X310827Y59449D02*
X322638D01*
G01X315551Y114567D02*
G03Y106693I0J-3937D01*
G01X352953Y219292D02*
X350984Y221260D01*
G01X322638Y274804D02*
G03X326575Y278741I0J3937D01*
G01X306890D02*
G03X310827Y274804I3937J0D01*
G01X296654D02*
G03X300591Y278741I0J3937D01*
G01X326575Y290552D02*
Y278741D01*
G01X306890D02*
Y290552D01*
G01X300591D02*
Y278741D01*
G01X322638Y274804D02*
X310827D01*
G01X308858Y264370D02*
G03X301378I-3740J0D01*
G01X350984Y235040D02*
X352953Y237008D01*
G01X308858D02*
Y264370D01*
G01X299409Y235040D02*
X301378Y237008D01*
G01D02*
Y264370D01*
G01X308858Y237008D02*
X310827Y235040D01*
G01X350984D02*
X310827D01*
G01Y294489D02*
G03X306890Y290552I0J-3937D01*
G01X326575D02*
G03X322638Y294489I-3937J0D01*
G01X300591Y290552D02*
G03X296654Y294489I-3937J0D01*
G01X310827D02*
X322638D01*
G01X315551Y349607D02*
G03Y341733I0J-3937D01*
G01X352953Y454331D02*
X350984Y456300D01*
G01X322638Y509843D02*
G03X326575Y513780I0J3937D01*
G01X306890D02*
G03X310827Y509843I3937J0D01*
G01Y529528D02*
G03X306890Y525591I0J-3937D01*
G01X326575D02*
G03X322638Y529528I-3937J0D01*
G01X300591Y525591D02*
G03X296654Y529528I-3937J0D01*
G01Y509843D02*
G03X300591Y513780I0J3937D01*
G01X326575Y525591D02*
Y513780D01*
G01X306890D02*
Y525591D01*
G01X300591D02*
Y513780D01*
G01X310827Y529528D02*
X322638D01*
G01Y509843D02*
X310827D01*
G01X308858Y499410D02*
G03X301378I-3740J0D01*
G01X350984Y470079D02*
X352953Y472048D01*
G01X308858D02*
Y499410D01*
G01X299409Y470079D02*
X301378Y472048D01*
G01D02*
Y499410D01*
G01X308858Y472048D02*
X310827Y470079D01*
G01X350984D02*
X310827D01*
G01X315551Y584646D02*
G03Y576772I0J-3937D01*
G01X352953Y689371D02*
X350984Y691339D01*
G01X381890Y37795D02*
G03X385827Y33858I3937J0D01*
G01X402953Y29921D02*
G03X399016Y33858I-3937J0D01*
G01X385827D02*
X399016D01*
G01X681299Y0D02*
X404921D01*
G01X402953Y1969D02*
X404921Y0D01*
G01X402953Y1969D02*
Y29921D01*
G01X381890Y102756D02*
Y37795D01*
G01X352953Y1969D02*
Y59941D01*
G01D02*
Y33858D01*
G01X385827Y106693D02*
G03X381890Y102756I0J-3937D01*
G01X374016D02*
G03X370079Y106693I-3937J0D01*
G01Y63878D02*
G03X374016Y67815I0J3937D01*
G01X356890Y63878D02*
G03X352953Y59941I0J-3937D01*
G01X374016Y102756D02*
Y67815D01*
G01X370079Y63878D02*
X356890D01*
G01X374016Y98524D02*
G03X381890I3937J0D01*
G01Y67815D02*
G03X374016I-3937J0D01*
G01X385827Y106693D02*
X525591D01*
G01X370079Y114567D02*
G03X374016Y118504I0J3937D01*
G01D02*
Y183465D01*
G01X381890Y118504D02*
G03X385827Y114567I3937J0D01*
G01Y157382D02*
G03X381890Y153445I0J-3937D01*
G01X399016Y157382D02*
G03X402953Y161319I0J3937D01*
G01X381890Y118504D02*
Y153445D01*
G01X402953Y219292D02*
Y161319D01*
G01D02*
Y187402D01*
G01X525591Y114567D02*
X385827D01*
G01Y157382D02*
X399016D01*
G01X374016Y153445D02*
G03X381890I3937J0D01*
G01Y122737D02*
G03X374016I-3937J0D01*
G01Y183465D02*
G03X370079Y187402I-3937J0D01*
G01X352953Y191339D02*
G03X356890Y187402I3937J0D01*
G01X370079D02*
X356890D01*
G01X352953Y219292D02*
Y191339D01*
G01X404921Y221260D02*
X402953Y219292D01*
G01X404921Y221260D02*
X445079D01*
G01X352953Y237008D02*
Y294981D01*
G01D02*
Y268898D01*
G01X381890Y272835D02*
G03X385827Y268898I3937J0D01*
G01X402953Y264961D02*
G03X399016Y268898I-3937J0D01*
G01X385827D02*
X399016D01*
G01X681299Y235040D02*
X404921D01*
G01X402953Y237008D02*
X404921Y235040D01*
G01X402953Y237008D02*
Y264961D01*
G01X381890Y337796D02*
Y272835D01*
G01X374016Y337796D02*
G03X370079Y341733I-3937J0D01*
G01Y298918D02*
G03X374016Y302855I0J3937D01*
G01X356890Y298918D02*
G03X352953Y294981I0J-3937D01*
G01X374016Y337796D02*
Y302855D01*
G01X370079Y298918D02*
X356890D01*
G01X385827Y341733D02*
G03X381890Y337796I0J-3937D01*
G01X385827Y341733D02*
X525591D01*
G01X374016Y333563D02*
G03X381890I3937J0D01*
G01Y302855D02*
G03X374016I-3937J0D01*
G01X381890Y353544D02*
G03X385827Y349607I3937J0D01*
G01Y392422D02*
G03X381890Y388485I0J-3937D01*
G01X399016Y392422D02*
G03X402953Y396359I0J3937D01*
G01X381890Y353544D02*
Y388485D01*
G01X402953Y454331D02*
Y396359D01*
G01D02*
Y422441D01*
G01X525591Y349607D02*
X385827D01*
G01Y392422D02*
X399016D01*
G01X370079Y349607D02*
G03X374016Y353544I0J3937D01*
G01D02*
Y418504D01*
G01Y388485D02*
G03X381890I3937J0D01*
G01Y357776D02*
G03X374016I-3937J0D01*
G01X404921Y456300D02*
X402953Y454331D01*
G01X404921Y456300D02*
X445079D01*
G01X374016Y418504D02*
G03X370079Y422441I-3937J0D01*
G01X352953Y426378D02*
G03X356890Y422441I3937J0D01*
G01X370079D02*
X356890D01*
G01X352953Y454331D02*
Y426378D01*
G01Y472048D02*
Y530020D01*
G01D02*
Y503937D01*
G01X381890Y507874D02*
G03X385827Y503937I3937J0D01*
G01X402953Y500000D02*
G03X399016Y503937I-3937J0D01*
G01X385827D02*
X399016D01*
G01X681299Y470079D02*
X404921D01*
G01X402953Y472048D02*
X404921Y470079D01*
G01X402953Y472048D02*
Y500000D01*
G01X381890Y572835D02*
Y507874D01*
G01X374016Y572835D02*
G03X370079Y576772I-3937J0D01*
G01Y533957D02*
G03X374016Y537894I0J3937D01*
G01X356890Y533957D02*
G03X352953Y530020I0J-3937D01*
G01X374016Y572835D02*
Y537894D01*
G01X370079Y533957D02*
X356890D01*
G01X385827Y576772D02*
G03X381890Y572835I0J-3937D01*
G01X385827Y576772D02*
X525591D01*
G01X381890Y588583D02*
G03X385827Y584646I3937J0D01*
G01X381890Y588583D02*
Y623524D01*
G01X525591Y584646D02*
X385827D01*
G01X370079D02*
G03X374016Y588583I0J3937D01*
G01D02*
Y653544D01*
G01Y568603D02*
G03X381890I3937J0D01*
G01Y537894D02*
G03X374016I-3937J0D01*
G01X385827Y627461D02*
G03X381890Y623524I0J-3937D01*
G01X399016Y627461D02*
G03X402953Y631398I0J3937D01*
G01Y689371D02*
Y631398D01*
G01D02*
Y657481D01*
G01X385827Y627461D02*
X399016D01*
G01X374016Y623524D02*
G03X381890I3937J0D01*
G01Y592816D02*
G03X374016I-3937J0D01*
G01X404921Y691339D02*
X402953Y689371D01*
G01X404921Y691339D02*
X445079D01*
G01X374016Y653544D02*
G03X370079Y657481I-3937J0D01*
G01X352953Y661418D02*
G03X356890Y657481I3937J0D01*
G01X370079D02*
X356890D01*
G01X352953Y689371D02*
Y661418D01*
G01X445079Y161811D02*
G03X449016Y165748I0J3937D01*
G01X429331D02*
G03X433268Y161811I3937J0D01*
G01X455315Y165748D02*
G03X459252Y161811I3937J0D01*
G01X471063D02*
G03X475000Y165748I0J3937D01*
G01X445079Y161811D02*
X433268D01*
G01X471063D02*
X459252D01*
G01X471063Y114567D02*
G03Y106693I0J-3937D01*
G01X440354D02*
G03Y114567I0J3937D01*
G01X433268Y181496D02*
G03X429331Y177559I0J-3937D01*
G01X449016D02*
G03X445079Y181496I-3937J0D01*
G01X459252D02*
G03X455315Y177559I0J-3937D01*
G01X475000D02*
G03X471063Y181496I-3937J0D01*
G01X429331Y165748D02*
Y177559D01*
G01X449016D02*
Y165748D01*
G01X455315D02*
Y177559D01*
G01X459252Y181496D02*
X471063D01*
G01X433268D02*
X445079D01*
G01X447047Y191930D02*
G03X454528I3740J0D01*
G01X447047Y219292D02*
Y191930D01*
G01X456496Y221260D02*
X454528Y219292D01*
G01D02*
Y191930D01*
G01X447047Y219292D02*
X445079Y221260D01*
G01X456496D02*
X732874D01*
G01X471063Y349607D02*
G03Y341733I0J-3937D01*
G01X440354D02*
G03Y349607I0J3937D01*
G01X445079Y396851D02*
G03X449016Y400788I0J3937D01*
G01X429331D02*
G03X433268Y396851I3937J0D01*
G01X455315Y400788D02*
G03X459252Y396851I3937J0D01*
G01X471063D02*
G03X475000Y400788I0J3937D01*
G01X429331D02*
Y412599D01*
G01X449016D02*
Y400788D01*
G01X455315D02*
Y412599D01*
G01X445079Y396851D02*
X433268D01*
G01X471063D02*
X459252D01*
G01X433268Y416536D02*
G03X429331Y412599I0J-3937D01*
G01X449016D02*
G03X445079Y416536I-3937J0D01*
G01X459252D02*
G03X455315Y412599I0J-3937D01*
G01X475000D02*
G03X471063Y416536I-3937J0D01*
G01X459252D02*
X471063D01*
G01X433268D02*
X445079D01*
G01X447047Y426969D02*
G03X454528I3740J0D01*
G01X447047Y454331D02*
Y426969D01*
G01X456496Y456300D02*
X454528Y454331D01*
G01D02*
Y426969D01*
G01X447047Y454331D02*
X445079Y456300D01*
G01X456496D02*
X732874D01*
G01X471063Y584646D02*
G03Y576772I0J-3937D01*
G01X440354D02*
G03Y584646I0J3937D01*
G01X433268Y651576D02*
G03X429331Y647639I0J-3937D01*
G01X449016D02*
G03X445079Y651576I-3937J0D01*
G01Y631891D02*
G03X449016Y635828I0J3937D01*
G01X429331D02*
G03X433268Y631891I3937J0D01*
G01X455315Y635828D02*
G03X459252Y631891I3937J0D01*
G01Y651576D02*
G03X455315Y647639I0J-3937D01*
G01X475000D02*
G03X471063Y651576I-3937J0D01*
G01Y631891D02*
G03X475000Y635828I0J3937D01*
G01X429331D02*
Y647639D01*
G01X449016D02*
Y635828D01*
G01X455315D02*
Y647639D01*
G01X445079Y631891D02*
X433268D01*
G01X471063D02*
X459252D01*
G01Y651576D02*
X471063D01*
G01X433268D02*
X445079D01*
G01X447047Y662009D02*
G03X454528I3740J0D01*
G01X447047Y689371D02*
Y662009D01*
G01X456496Y691339D02*
X454528Y689371D01*
G01D02*
Y662009D01*
G01X447047Y689371D02*
X445079Y691339D01*
G01X456496D02*
X732874D01*
G01X529528Y102756D02*
G03X533465Y98819I3937J0D01*
G01X529528Y102756D02*
G03X525591Y106693I-3937J0D01*
G01X529528Y102756D02*
G03X533465Y98819I3937J0D01*
G01X529528Y102756D02*
G03X525591Y106693I-3937J0D01*
G01X529528Y102756D02*
G03X533465Y98819I3937J0D01*
G01X529528Y102756D02*
G03X525591Y106693I-3937J0D01*
G01X533465Y98819D02*
X604331D01*
G01X525591Y106693D02*
X494094D01*
G01X497047Y161811D02*
G03X500984Y165748I0J3937D01*
G01X481299D02*
G03X485236Y161811I3937J0D01*
G01X497047D02*
X485236D01*
G01X533465Y122441D02*
G03X529528Y118504I0J-3937D01*
G01X525591Y114567D02*
G03X529528Y118504I0J3937D01*
G01X525591Y114567D02*
X494094D01*
G01X525591D02*
G03X529528Y118504I0J3937D01*
G01X533465Y122441D02*
G03X529528Y118504I0J-3937D01*
G01X533465Y122441D02*
G03X529528Y118504I0J-3937D01*
G01X525591Y114567D02*
G03X529528Y118504I0J3937D01*
G01X604331Y122441D02*
X533465D01*
G01X485236Y181496D02*
G03X481299Y177559I0J-3937D01*
G01X500984D02*
G03X497047Y181496I-3937J0D01*
G01X475000Y177559D02*
Y165748D01*
G01X481299D02*
Y177559D01*
G01X500984D02*
Y165748D01*
G01X485236Y181496D02*
X497047D01*
G01X529528Y337796D02*
G03X533465Y333859I3937J0D01*
G01X529528Y337796D02*
G03X525591Y341733I-3937J0D01*
G01D02*
X494094D01*
G01X529528Y337796D02*
G03X533465Y333859I3937J0D01*
G01X529528Y337796D02*
G03X525591Y341733I-3937J0D01*
G01X529528Y337796D02*
G03X533465Y333859I3937J0D01*
G01X529528Y337796D02*
G03X525591Y341733I-3937J0D01*
G01X533465Y333859D02*
X604331D01*
G01X497047Y396851D02*
G03X500984Y400788I0J3937D01*
G01X481299D02*
G03X485236Y396851I3937J0D01*
G01X475000Y412599D02*
Y400788D01*
G01X481299D02*
Y412599D01*
G01X500984D02*
Y400788D01*
G01X497047Y396851D02*
X485236D01*
G01X533465Y357481D02*
G03X529528Y353544I0J-3937D01*
G01X525591Y349607D02*
G03X529528Y353544I0J3937D01*
G01X525591Y349607D02*
X494094D01*
G01X525591D02*
G03X529528Y353544I0J3937D01*
G01X533465Y357481D02*
G03X529528Y353544I0J-3937D01*
G01X533465Y357481D02*
G03X529528Y353544I0J-3937D01*
G01X525591Y349607D02*
G03X529528Y353544I0J3937D01*
G01X604331Y357481D02*
X533465D01*
G01X485236Y416536D02*
G03X481299Y412599I0J-3937D01*
G01X500984D02*
G03X497047Y416536I-3937J0D01*
G01X485236D02*
X497047D01*
G01X529528Y572835D02*
G03X533465Y568898I3937J0D01*
G01X529528Y572835D02*
G03X525591Y576772I-3937J0D01*
G01D02*
X494094D01*
G01X529528Y572835D02*
G03X533465Y568898I3937J0D01*
G01X529528Y572835D02*
G03X525591Y576772I-3937J0D01*
G01X529528Y572835D02*
G03X533465Y568898I3937J0D01*
G01X529528Y572835D02*
G03X525591Y576772I-3937J0D01*
G01X533465Y568898D02*
X604331D01*
G01X533465Y592520D02*
G03X529528Y588583I0J-3937D01*
G01X525591Y584646D02*
G03X529528Y588583I0J3937D01*
G01X525591Y584646D02*
X494094D01*
G01X525591D02*
G03X529528Y588583I0J3937D01*
G01X533465Y592520D02*
G03X529528Y588583I0J-3937D01*
G01X533465Y592520D02*
G03X529528Y588583I0J-3937D01*
G01X525591Y584646D02*
G03X529528Y588583I0J3937D01*
G01X485236Y651576D02*
G03X481299Y647639I0J-3937D01*
G01X500984D02*
G03X497047Y651576I-3937J0D01*
G01Y631891D02*
G03X500984Y635828I0J3937D01*
G01X481299D02*
G03X485236Y631891I3937J0D01*
G01X475000Y647639D02*
Y635828D01*
G01X481299D02*
Y647639D01*
G01X500984D02*
Y635828D01*
G01X497047Y631891D02*
X485236D01*
G01Y651576D02*
X497047D01*
G01X604331Y592520D02*
X533465D01*
G01X652559Y39764D02*
G03X656496Y43701I0J3937D01*
G01X636811D02*
G03X640748Y39764I3937J0D01*
G01X652559D02*
X640748D01*
G01Y59449D02*
G03X636811Y55512I0J-3937D01*
G01X656496D02*
G03X652559Y59449I-3937J0D01*
G01X656496Y55512D02*
Y43701D01*
G01X636811D02*
Y55512D01*
G01X640748Y59449D02*
X652559D01*
G01X604331Y98819D02*
G03X608268Y102756I0J3937D01*
G01X612205Y106693D02*
G03X608268Y102756I0J-3937D01*
G01X612205Y106693D02*
G03X608268Y102756I0J-3937D01*
G01X604331Y98819D02*
G03X608268Y102756I0J3937D01*
G01X604331Y98819D02*
G03X608268Y102756I0J3937D01*
G01X612205Y106693D02*
G03X608268Y102756I0J-3937D01*
G01X612205Y106693D02*
X643701D01*
G01X612205D02*
X751969D01*
G01X608268Y118504D02*
G03X604331Y122441I-3937J0D01*
G01X608268Y118504D02*
G03X612205Y114567I3937J0D01*
G01D02*
X643701D01*
G01X608268Y118504D02*
G03X604331Y122441I-3937J0D01*
G01X608268Y118504D02*
G03X612205Y114567I3937J0D01*
G01X608268Y118504D02*
G03X604331Y122441I-3937J0D01*
G01X608268Y118504D02*
G03X612205Y114567I3937J0D01*
G01X751969D02*
X612205D01*
G01X652559Y274804D02*
G03X656496Y278741I0J3937D01*
G01X636811D02*
G03X640748Y274804I3937J0D01*
G01X656496Y290552D02*
Y278741D01*
G01X636811D02*
Y290552D01*
G01X652559Y274804D02*
X640748D01*
G01Y294489D02*
G03X636811Y290552I0J-3937D01*
G01X656496D02*
G03X652559Y294489I-3937J0D01*
G01X640748D02*
X652559D01*
G01X604331Y333859D02*
G03X608268Y337796I0J3937D01*
G01X612205Y341733D02*
G03X608268Y337796I0J-3937D01*
G01X612205Y341733D02*
X643701D01*
G01X612205D02*
G03X608268Y337796I0J-3937D01*
G01X604331Y333859D02*
G03X608268Y337796I0J3937D01*
G01X604331Y333859D02*
G03X608268Y337796I0J3937D01*
G01X612205Y341733D02*
G03X608268Y337796I0J-3937D01*
G01X612205Y341733D02*
X751969D01*
G01X608268Y353544D02*
G03X604331Y357481I-3937J0D01*
G01X608268Y353544D02*
G03X612205Y349607I3937J0D01*
G01D02*
X643701D01*
G01X608268Y353544D02*
G03X604331Y357481I-3937J0D01*
G01X608268Y353544D02*
G03X612205Y349607I3937J0D01*
G01X608268Y353544D02*
G03X604331Y357481I-3937J0D01*
G01X608268Y353544D02*
G03X612205Y349607I3937J0D01*
G01X751969D02*
X612205D01*
G01X652559Y509843D02*
G03X656496Y513780I0J3937D01*
G01X636811D02*
G03X640748Y509843I3937J0D01*
G01Y529528D02*
G03X636811Y525591I0J-3937D01*
G01X656496D02*
G03X652559Y529528I-3937J0D01*
G01X656496Y525591D02*
Y513780D01*
G01X636811D02*
Y525591D01*
G01X640748Y529528D02*
X652559D01*
G01Y509843D02*
X640748D01*
G01X604331Y568898D02*
G03X608268Y572835I0J3937D01*
G01X612205Y576772D02*
G03X608268Y572835I0J-3937D01*
G01X612205Y576772D02*
X643701D01*
G01X612205D02*
G03X608268Y572835I0J-3937D01*
G01X604331Y568898D02*
G03X608268Y572835I0J3937D01*
G01X604331Y568898D02*
G03X608268Y572835I0J3937D01*
G01X612205Y576772D02*
G03X608268Y572835I0J-3937D01*
G01X612205Y576772D02*
X751969D01*
G01X608268Y588583D02*
G03X604331Y592520I-3937J0D01*
G01X608268Y588583D02*
G03X612205Y584646I3937J0D01*
G01D02*
X643701D01*
G01X608268Y588583D02*
G03X604331Y592520I-3937J0D01*
G01X608268Y588583D02*
G03X612205Y584646I3937J0D01*
G01X608268Y588583D02*
G03X604331Y592520I-3937J0D01*
G01X608268Y588583D02*
G03X612205Y584646I3937J0D01*
G01X751969D02*
X612205D01*
G01X704528Y39764D02*
G03X708465Y43701I0J3937D01*
G01X688780D02*
G03X692717Y39764I3937J0D01*
G01X678543D02*
G03X682480Y43701I0J3937D01*
G01X662795D02*
G03X666732Y39764I3937J0D01*
G01X678543D02*
X666732D01*
G01X704528D02*
X692717D01*
G01X690748Y29331D02*
G03X683268I-3740J0D01*
G01X690748Y1969D02*
Y29331D01*
G01X681299Y0D02*
X683268Y1969D01*
G01D02*
Y29331D01*
G01X690748Y1969D02*
X692717Y0D01*
G01X732874D02*
X692717D01*
G01Y59449D02*
G03X688780Y55512I0J-3937D01*
G01X708465D02*
G03X704528Y59449I-3937J0D01*
G01X682480Y55512D02*
G03X678543Y59449I-3937J0D01*
G01X666732D02*
G03X662795Y55512I0J-3937D01*
G01X708465D02*
Y43701D01*
G01X688780D02*
Y55512D01*
G01X682480D02*
Y43701D01*
G01X662795D02*
Y55512D01*
G01X692717Y59449D02*
X704528D01*
G01X666732D02*
X678543D01*
G01X697441Y114567D02*
G03Y106693I0J-3937D01*
G01X666732D02*
G03Y114567I0J3937D01*
G01X704528Y274804D02*
G03X708465Y278741I0J3937D01*
G01X688780D02*
G03X692717Y274804I3937J0D01*
G01X678543D02*
G03X682480Y278741I0J3937D01*
G01X662795D02*
G03X666732Y274804I3937J0D01*
G01X708465Y290552D02*
Y278741D01*
G01X688780D02*
Y290552D01*
G01X682480D02*
Y278741D01*
G01X662795D02*
Y290552D01*
G01X678543Y274804D02*
X666732D01*
G01X704528D02*
X692717D01*
G01X690748Y264370D02*
G03X683268I-3740J0D01*
G01X690748Y237008D02*
Y264370D01*
G01X681299Y235040D02*
X683268Y237008D01*
G01D02*
Y264370D01*
G01X690748Y237008D02*
X692717Y235040D01*
G01X732874D02*
X692717D01*
G01Y294489D02*
G03X688780Y290552I0J-3937D01*
G01X708465D02*
G03X704528Y294489I-3937J0D01*
G01X682480Y290552D02*
G03X678543Y294489I-3937J0D01*
G01X666732D02*
G03X662795Y290552I0J-3937D01*
G01X692717Y294489D02*
X704528D01*
G01X666732D02*
X678543D01*
G01X697441Y349607D02*
G03Y341733I0J-3937D01*
G01X666732D02*
G03Y349607I0J3937D01*
G01X704528Y509843D02*
G03X708465Y513780I0J3937D01*
G01X688780D02*
G03X692717Y509843I3937J0D01*
G01Y529528D02*
G03X688780Y525591I0J-3937D01*
G01X708465D02*
G03X704528Y529528I-3937J0D01*
G01X682480Y525591D02*
G03X678543Y529528I-3937J0D01*
G01Y509843D02*
G03X682480Y513780I0J3937D01*
G01X662795D02*
G03X666732Y509843I3937J0D01*
G01Y529528D02*
G03X662795Y525591I0J-3937D01*
G01X708465D02*
Y513780D01*
G01X688780D02*
Y525591D01*
G01X682480D02*
Y513780D01*
G01X662795D02*
Y525591D01*
G01X692717Y529528D02*
X704528D01*
G01X666732D02*
X678543D01*
G01Y509843D02*
X666732D01*
G01X704528D02*
X692717D01*
G01X690748Y499410D02*
G03X683268I-3740J0D01*
G01X690748Y472048D02*
Y499410D01*
G01X681299Y470079D02*
X683268Y472048D01*
G01D02*
Y499410D01*
G01X690748Y472048D02*
X692717Y470079D01*
G01X732874D02*
X692717D01*
G01X697441Y584646D02*
G03Y576772I0J-3937D01*
G01X666732D02*
G03Y584646I0J3937D01*
G01X734843Y1969D02*
Y59941D01*
G01D02*
Y33858D01*
G01X732874Y0D02*
X734843Y1969D01*
G01X762744Y17317D02*
G03I-4292J0D01*
G01X775591Y553149D02*
Y15000D01*
G01X760591Y0D02*
G03X775591Y15000I0J15000D01*
G01X742717Y0D02*
Y56004D01*
G01Y0D02*
X760591D01*
G01X755906Y102756D02*
G03X751969Y106693I-3937J0D01*
G01Y63878D02*
G03X755906Y67815I0J3937D01*
G01X738780Y63878D02*
G03X734843Y59941I0J-3937D01*
G01X755906Y102756D02*
Y67815D01*
G01X751969Y63878D02*
X738780D01*
G01X763780Y152761D02*
Y98517D01*
G01Y67822D02*
Y67803D01*
G01X751969Y56004D02*
X742717D01*
G01X751969D02*
G03X763780Y67815I0J11811D01*
G01D02*
G03X755906I-3937J0D01*
G01Y98524D02*
G03X763780I3937J0D01*
G01X751969Y114567D02*
G03X755906Y118504I0J3937D01*
G01D02*
Y183465D01*
G01X763780Y152756D02*
G03X755906I-3937J0D01*
G01Y183465D02*
G03X751969Y187402I-3937J0D01*
G01X734843Y191339D02*
G03X738780Y187402I3937J0D01*
G01X751969D02*
X738780D01*
G01X734843Y219292D02*
X732874Y221260D01*
G01X734843Y219292D02*
Y191339D01*
G01X755906Y183465D02*
G03X763780I3937J0D01*
G01Y302855D02*
Y183460D01*
G01X734843Y237008D02*
Y294981D01*
G01D02*
Y268898D01*
G01X732874Y235040D02*
X734843Y237008D01*
G01X755906Y337796D02*
G03X751969Y341733I-3937J0D01*
G01Y298918D02*
G03X755906Y302855I0J3937D01*
G01X738780Y298918D02*
G03X734843Y294981I0J-3937D01*
G01X755906Y337796D02*
Y302855D01*
G01X751969Y298918D02*
X738780D01*
G01X763780Y387796D02*
Y333559D01*
G01Y302855D02*
G03X755906I-3937J0D01*
G01Y333563D02*
G03X763780I3937J0D01*
G01X751969Y349607D02*
G03X755906Y353544I0J3937D01*
G01D02*
Y418504D01*
G01X763780Y387796D02*
G03X755906I-3937J0D01*
G01Y418504D02*
G03X751969Y422441I-3937J0D01*
G01X734843Y426378D02*
G03X738780Y422441I3937J0D01*
G01X751969D02*
X738780D01*
G01X734843Y454331D02*
X732874Y456300D01*
G01X734843Y454331D02*
Y426378D01*
G01X763780Y537894D02*
Y418504D01*
G01X755906Y418505D02*
G03X763780I3937J0D01*
G01X734843Y472048D02*
Y530020D01*
G01D02*
Y503937D01*
G01X732874Y470079D02*
X734843Y472048D01*
G01X755906Y572835D02*
G03X751969Y576772I-3937J0D01*
G01Y533957D02*
G03X755906Y537894I0J3937D01*
G01X738780Y533957D02*
G03X734843Y530020I0J-3937D01*
G01X755906Y572835D02*
Y537894D01*
G01X751969Y533957D02*
X738780D01*
G01X751969Y584646D02*
G03X755906Y588583I0J3937D01*
G01D02*
Y653544D01*
G01X775591Y561023D02*
G03Y553149I0J-3937D01*
G01X763780Y537894D02*
G03X755906I-3937J0D01*
G01Y568603D02*
G03X763780I3937J0D01*
G01X775591Y676339D02*
Y561023D01*
G01X763780Y622835D02*
Y568603D01*
G01Y622835D02*
G03X755906I-3937J0D01*
G01Y653544D02*
G03X763780I3937J0D01*
G01X755906D02*
G03X751969Y657481I-3937J0D01*
G01X734843Y661418D02*
G03X738780Y657481I3937J0D01*
G01X751969D02*
X738780D01*
G01X734843Y689371D02*
X732874Y691339D01*
G01X734843Y689371D02*
Y661418D01*
G01X760014Y677788D02*
G03I-4292J0D01*
G01X775591Y676339D02*
G03X760591Y691339I-15000J0D01*
G01X751969Y665355D02*
X742717D01*
G01X763780Y653544D02*
G03X751969Y665355I-11811J0D01*
G01X742717Y691339D02*
X760591D01*
G01X742717Y665355D02*
Y691339D01*
M02*
